(kicad_pcb
	(version 20260206)
	(generator "pcbnew")
	(generator_version "10.0")
	(general
		(thickness 1.6)
		(legacy_teardrops no)
	)
	(paper "A4")
	(title_block
		(title "03242023_DA0F0TMBIJ0_F0T_Motherboard_J_brd_V01_OCP.brd")
		(comment 1 "Grand Teton / footprint 1229 of 6105 (J4), pads 1-112 of 291")
	)
	(layers
		(0 "F.Cu" signal "TOP")
		(4 "In1.Cu" signal "GND")
		(6 "In2.Cu" signal "IN1")
		(8 "In3.Cu" signal "GND1")
		(10 "In4.Cu" signal "IN2")
		(12 "In5.Cu" signal "GND2")
		(14 "In6.Cu" signal "IN3")
		(16 "In7.Cu" signal "GND3")
		(18 "In8.Cu" signal "VCC")
		(20 "In9.Cu" signal "VCC1")
		(22 "In10.Cu" signal "GND4")
		(24 "In11.Cu" signal "IN4")
		(26 "In12.Cu" signal "GND5")
		(28 "In13.Cu" signal "IN5")
		(30 "In14.Cu" signal "GND6")
		(32 "In15.Cu" signal "IN6")
		(34 "In16.Cu" signal "GND7")
		(2 "B.Cu" signal "BOTTOM")
		(9 "F.Adhes" user "F.Adhesive")
		(11 "B.Adhes" user "B.Adhesive")
		(13 "F.Paste" user "Package Geometry/Pastemask Top")
		(15 "B.Paste" user "Package Geometry/Pastemask Bottom")
		(5 "F.SilkS" user "Ref Des/Silkscreen Top")
		(7 "B.SilkS" user "Ref Des/Silkscreen Bottom")
		(1 "F.Mask" user "Board Geometry/Soldermask Top")
		(3 "B.Mask" user "Board Geometry/Soldermask Bottom")
		(17 "Dwgs.User" user "User.Drawings")
		(19 "Cmts.User" user "User.Comments")
		(21 "Eco1.User" user "User.Eco1")
		(23 "Eco2.User" user "User.Eco2")
		(25 "Edge.Cuts" user "Board Geometry/Outline")
		(27 "Margin" user)
		(31 "F.CrtYd" user "Package Geometry/Place Bound Top")
		(29 "B.CrtYd" user "Package Geometry/Place Bound Bottom")
		(35 "F.Fab" user "Ref Des/Assembly Top")
		(33 "B.Fab" user "Ref Des/Assembly Bottom")
	)
	(footprint ""
		(layer "F.Cu")
		(at 295.849548 -258.091686)
		(property "Reference" "J4"
			(at -3.683 -81.702148 0)
			(unlocked yes)
			(layer "F.SilkS")
			(effects
				(font
					(size 0.7874 0.5842)
					(thickness 0.1524)
				)
				(justify left)
			)
		)
		(property "Value" ""
			(at 0 0 0)
			(layer "F.Fab")
			(effects
				(font
					(size 1.27 1.27)
				)
			)
		)
		(duplicate_pad_numbers_are_jumpers no)
		(pad "1" smd rect
			(at -2.050034 -63.324994 270)
			(size 0.519938 1.4986)
			(layers "F.Cu" "F.Mask" "F.Paste")
			(net "P12V_S3_AUX_CPU0_NVDIMM")
		)
		(pad "2" smd rect
			(at -2.050034 -62.47511 270)
			(size 0.519938 1.4986)
			(layers "F.Cu" "F.Mask" "F.Paste")
			(net "TP_CHB_CPU0_DIMM2_FRU_0")
		)
		(pad "3" smd rect
			(at -2.050034 -61.624972 270)
			(size 0.519938 1.4986)
			(layers "F.Cu" "F.Mask" "F.Paste")
			(net "P3V3_AUX")
		)
		(pad "4" smd rect
			(at -2.050034 -60.775088 270)
			(size 0.519938 1.4986)
			(layers "F.Cu" "F.Mask" "F.Paste")
			(net "I3C_SPD_DDRABCD_CPU0_LVC1_SCL_3")
		)
		(pad "5" smd rect
			(at -2.050034 -59.92495 270)
			(size 0.519938 1.4986)
			(layers "F.Cu" "F.Mask" "F.Paste")
			(net "I3C_SPD_DDRABCD_CPU0_LVC1_SDA")
		)
		(pad "6" smd rect
			(at -2.050034 -59.075066 270)
			(size 0.519938 1.4986)
			(layers "F.Cu" "F.Mask" "F.Paste")
			(net "GND")
		)
		(pad "7" smd rect
			(at -2.050034 -58.224928 270)
			(size 0.519938 1.4986)
			(layers "F.Cu" "F.Mask" "F.Paste")
			(net "M_B_CPU0_SA_DQ<0>")
		)
		(pad "8" smd rect
			(at -2.050034 -57.375044 270)
			(size 0.519938 1.4986)
			(layers "F.Cu" "F.Mask" "F.Paste")
			(net "GND")
		)
		(pad "9" smd rect
			(at -2.050034 -56.524906 270)
			(size 0.519938 1.4986)
			(layers "F.Cu" "F.Mask" "F.Paste")
			(net "M_B_CPU0_SA_DQ<1>")
		)
		(pad "10" smd rect
			(at -2.050034 -55.675022 270)
			(size 0.519938 1.4986)
			(layers "F.Cu" "F.Mask" "F.Paste")
			(net "GND")
		)
		(pad "11" smd rect
			(at -2.050034 -54.824884 270)
			(size 0.519938 1.4986)
			(layers "F.Cu" "F.Mask" "F.Paste")
			(net "M_B_CPU0_SA_DQS_DP<0>")
		)
		(pad "12" smd rect
			(at -2.050034 -53.975 270)
			(size 0.519938 1.4986)
			(layers "F.Cu" "F.Mask" "F.Paste")
			(net "M_B_CPU0_SA_DQS_DN<0>")
		)
		(pad "13" smd rect
			(at -2.050034 -53.125116 270)
			(size 0.519938 1.4986)
			(layers "F.Cu" "F.Mask" "F.Paste")
			(net "GND")
		)
		(pad "14" smd rect
			(at -2.050034 -52.274978 270)
			(size 0.519938 1.4986)
			(layers "F.Cu" "F.Mask" "F.Paste")
			(net "M_B_CPU0_SA_DQ<4>")
		)
		(pad "15" smd rect
			(at -2.050034 -51.425094 270)
			(size 0.519938 1.4986)
			(layers "F.Cu" "F.Mask" "F.Paste")
			(net "GND")
		)
		(pad "16" smd rect
			(at -2.050034 -50.574956 270)
			(size 0.519938 1.4986)
			(layers "F.Cu" "F.Mask" "F.Paste")
			(net "M_B_CPU0_SA_DQ<5>")
		)
		(pad "17" smd rect
			(at -2.050034 -49.725072 270)
			(size 0.519938 1.4986)
			(layers "F.Cu" "F.Mask" "F.Paste")
			(net "GND")
		)
		(pad "18" smd rect
			(at -2.050034 -48.874934 270)
			(size 0.519938 1.4986)
			(layers "F.Cu" "F.Mask" "F.Paste")
			(net "M_B_CPU0_SA_DQ<8>")
		)
		(pad "19" smd rect
			(at -2.050034 -48.02505 270)
			(size 0.519938 1.4986)
			(layers "F.Cu" "F.Mask" "F.Paste")
			(net "GND")
		)
		(pad "20" smd rect
			(at -2.050034 -47.174912 270)
			(size 0.519938 1.4986)
			(layers "F.Cu" "F.Mask" "F.Paste")
			(net "M_B_CPU0_SA_DQ<9>")
		)
		(pad "21" smd rect
			(at -2.050034 -46.325028 270)
			(size 0.519938 1.4986)
			(layers "F.Cu" "F.Mask" "F.Paste")
			(net "GND")
		)
		(pad "22" smd rect
			(at -2.050034 -45.47489 270)
			(size 0.519938 1.4986)
			(layers "F.Cu" "F.Mask" "F.Paste")
			(net "M_B_CPU0_SA_DQS_DP<1>")
		)
		(pad "23" smd rect
			(at -2.050034 -44.625006 270)
			(size 0.519938 1.4986)
			(layers "F.Cu" "F.Mask" "F.Paste")
			(net "M_B_CPU0_SA_DQS_DN<1>")
		)
		(pad "24" smd rect
			(at -2.050034 -43.775122 270)
			(size 0.519938 1.4986)
			(layers "F.Cu" "F.Mask" "F.Paste")
			(net "GND")
		)
		(pad "25" smd rect
			(at -2.050034 -42.924984 270)
			(size 0.519938 1.4986)
			(layers "F.Cu" "F.Mask" "F.Paste")
			(net "M_B_CPU0_SA_DQ<12>")
		)
		(pad "26" smd rect
			(at -2.050034 -42.0751 270)
			(size 0.519938 1.4986)
			(layers "F.Cu" "F.Mask" "F.Paste")
			(net "GND")
		)
		(pad "27" smd rect
			(at -2.050034 -41.224962 270)
			(size 0.519938 1.4986)
			(layers "F.Cu" "F.Mask" "F.Paste")
			(net "M_B_CPU0_SA_DQ<13>")
		)
		(pad "28" smd rect
			(at -2.050034 -40.375078 270)
			(size 0.519938 1.4986)
			(layers "F.Cu" "F.Mask" "F.Paste")
			(net "GND")
		)
		(pad "29" smd rect
			(at -2.050034 -39.52494 270)
			(size 0.519938 1.4986)
			(layers "F.Cu" "F.Mask" "F.Paste")
			(net "M_B_CPU0_SA_DQ<16>")
		)
		(pad "30" smd rect
			(at -2.050034 -38.675056 270)
			(size 0.519938 1.4986)
			(layers "F.Cu" "F.Mask" "F.Paste")
			(net "GND")
		)
		(pad "31" smd rect
			(at -2.050034 -37.824918 270)
			(size 0.519938 1.4986)
			(layers "F.Cu" "F.Mask" "F.Paste")
			(net "M_B_CPU0_SA_DQ<17>")
		)
		(pad "32" smd rect
			(at -2.050034 -36.975034 270)
			(size 0.519938 1.4986)
			(layers "F.Cu" "F.Mask" "F.Paste")
			(net "GND")
		)
		(pad "33" smd rect
			(at -2.050034 -36.124896 270)
			(size 0.519938 1.4986)
			(layers "F.Cu" "F.Mask" "F.Paste")
			(net "M_B_CPU0_SA_DQS_DP<2>")
		)
		(pad "34" smd rect
			(at -2.050034 -35.275012 270)
			(size 0.519938 1.4986)
			(layers "F.Cu" "F.Mask" "F.Paste")
			(net "M_B_CPU0_SA_DQS_DN<2>")
		)
		(pad "35" smd rect
			(at -2.050034 -34.425128 270)
			(size 0.519938 1.4986)
			(layers "F.Cu" "F.Mask" "F.Paste")
			(net "GND")
		)
		(pad "36" smd rect
			(at -2.050034 -33.57499 270)
			(size 0.519938 1.4986)
			(layers "F.Cu" "F.Mask" "F.Paste")
			(net "M_B_CPU0_SA_DQ<20>")
		)
		(pad "37" smd rect
			(at -2.050034 -32.725106 270)
			(size 0.519938 1.4986)
			(layers "F.Cu" "F.Mask" "F.Paste")
			(net "GND")
		)
		(pad "38" smd rect
			(at -2.050034 -31.874968 270)
			(size 0.519938 1.4986)
			(layers "F.Cu" "F.Mask" "F.Paste")
			(net "M_B_CPU0_SA_DQ<21>")
		)
		(pad "39" smd rect
			(at -2.050034 -31.025084 270)
			(size 0.519938 1.4986)
			(layers "F.Cu" "F.Mask" "F.Paste")
			(net "GND")
		)
		(pad "40" smd rect
			(at -2.050034 -30.174946 270)
			(size 0.519938 1.4986)
			(layers "F.Cu" "F.Mask" "F.Paste")
			(net "M_B_CPU0_SA_DQ<24>")
		)
		(pad "41" smd rect
			(at -2.050034 -29.325062 270)
			(size 0.519938 1.4986)
			(layers "F.Cu" "F.Mask" "F.Paste")
			(net "GND")
		)
		(pad "42" smd rect
			(at -2.050034 -28.474924 270)
			(size 0.519938 1.4986)
			(layers "F.Cu" "F.Mask" "F.Paste")
			(net "M_B_CPU0_SA_DQ<25>")
		)
		(pad "43" smd rect
			(at -2.050034 -27.62504 270)
			(size 0.519938 1.4986)
			(layers "F.Cu" "F.Mask" "F.Paste")
			(net "GND")
		)
		(pad "44" smd rect
			(at -2.050034 -26.774902 270)
			(size 0.519938 1.4986)
			(layers "F.Cu" "F.Mask" "F.Paste")
			(net "M_B_CPU0_SA_DQS_DP<3>")
		)
		(pad "45" smd rect
			(at -2.050034 -25.925018 270)
			(size 0.519938 1.4986)
			(layers "F.Cu" "F.Mask" "F.Paste")
			(net "M_B_CPU0_SA_DQS_DN<3>")
		)
		(pad "46" smd rect
			(at -2.050034 -25.07488 270)
			(size 0.519938 1.4986)
			(layers "F.Cu" "F.Mask" "F.Paste")
			(net "GND")
		)
		(pad "47" smd rect
			(at -2.050034 -24.224996 270)
			(size 0.519938 1.4986)
			(layers "F.Cu" "F.Mask" "F.Paste")
			(net "M_B_CPU0_SA_DQ<28>")
		)
		(pad "48" smd rect
			(at -2.050034 -23.375112 270)
			(size 0.519938 1.4986)
			(layers "F.Cu" "F.Mask" "F.Paste")
			(net "GND")
		)
		(pad "49" smd rect
			(at -2.050034 -22.524974 270)
			(size 0.519938 1.4986)
			(layers "F.Cu" "F.Mask" "F.Paste")
			(net "M_B_CPU0_SA_DQ<29>")
		)
		(pad "50" smd rect
			(at -2.050034 -21.67509 270)
			(size 0.519938 1.4986)
			(layers "F.Cu" "F.Mask" "F.Paste")
			(net "GND")
		)
		(pad "51" smd rect
			(at -2.050034 -20.824952 270)
			(size 0.519938 1.4986)
			(layers "F.Cu" "F.Mask" "F.Paste")
			(net "M_B_CPU0_SA_CB<0>")
		)
		(pad "52" smd rect
			(at -2.050034 -19.975068 270)
			(size 0.519938 1.4986)
			(layers "F.Cu" "F.Mask" "F.Paste")
			(net "GND")
		)
		(pad "53" smd rect
			(at -2.050034 -19.12493 270)
			(size 0.519938 1.4986)
			(layers "F.Cu" "F.Mask" "F.Paste")
			(net "M_B_CPU0_SA_CB<1>")
		)
		(pad "54" smd rect
			(at -2.050034 -18.275046 270)
			(size 0.519938 1.4986)
			(layers "F.Cu" "F.Mask" "F.Paste")
			(net "GND")
		)
		(pad "55" smd rect
			(at -2.050034 -17.424908 270)
			(size 0.519938 1.4986)
			(layers "F.Cu" "F.Mask" "F.Paste")
			(net "M_B_CPU0_SA_DQS_DP<4>")
		)
		(pad "56" smd rect
			(at -2.050034 -16.575024 270)
			(size 0.519938 1.4986)
			(layers "F.Cu" "F.Mask" "F.Paste")
			(net "M_B_CPU0_SA_DQS_DN<4>")
		)
		(pad "57" smd rect
			(at -2.050034 -15.724886 270)
			(size 0.519938 1.4986)
			(layers "F.Cu" "F.Mask" "F.Paste")
			(net "GND")
		)
		(pad "58" smd rect
			(at -2.050034 -14.875002 270)
			(size 0.519938 1.4986)
			(layers "F.Cu" "F.Mask" "F.Paste")
			(net "M_B_CPU0_SA_CB<4>")
		)
		(pad "59" smd rect
			(at -2.050034 -14.025118 270)
			(size 0.519938 1.4986)
			(layers "F.Cu" "F.Mask" "F.Paste")
			(net "GND")
		)
		(pad "60" smd rect
			(at -2.050034 -13.17498 270)
			(size 0.519938 1.4986)
			(layers "F.Cu" "F.Mask" "F.Paste")
			(net "M_B_CPU0_SA_CB<5>")
		)
		(pad "61" smd rect
			(at -2.050034 -12.325096 270)
			(size 0.519938 1.4986)
			(layers "F.Cu" "F.Mask" "F.Paste")
			(net "GND")
		)
		(pad "62" smd rect
			(at -2.050034 -11.474958 270)
			(size 0.519938 1.4986)
			(layers "F.Cu" "F.Mask" "F.Paste")
			(net "M_B_CPU0_ALERT_N")
		)
		(pad "63" smd rect
			(at -2.050034 -10.625074 270)
			(size 0.519938 1.4986)
			(layers "F.Cu" "F.Mask" "F.Paste")
			(net "GND")
		)
		(pad "64" smd rect
			(at -2.050034 -9.774936 270)
			(size 0.519938 1.4986)
			(layers "F.Cu" "F.Mask" "F.Paste")
			(net "M_B_CPU0_SA_CS_N<2>")
		)
		(pad "65" smd rect
			(at -2.050034 -8.925052 270)
			(size 0.519938 1.4986)
			(layers "F.Cu" "F.Mask" "F.Paste")
			(net "GND")
		)
		(pad "66" smd rect
			(at -2.050034 -8.074914 270)
			(size 0.519938 1.4986)
			(layers "F.Cu" "F.Mask" "F.Paste")
			(net "M_B_CPU0_SA_CA<0>")
		)
		(pad "67" smd rect
			(at -2.050034 -7.22503 270)
			(size 0.519938 1.4986)
			(layers "F.Cu" "F.Mask" "F.Paste")
			(net "GND")
		)
		(pad "68" smd rect
			(at -2.050034 -6.374892 270)
			(size 0.519938 1.4986)
			(layers "F.Cu" "F.Mask" "F.Paste")
			(net "M_B_CPU0_SA_CA<2>")
		)
		(pad "69" smd rect
			(at -2.050034 -5.525008 270)
			(size 0.519938 1.4986)
			(layers "F.Cu" "F.Mask" "F.Paste")
			(net "GND")
		)
		(pad "70" smd rect
			(at -2.050034 -4.675124 270)
			(size 0.519938 1.4986)
			(layers "F.Cu" "F.Mask" "F.Paste")
			(net "M_B_CPU0_SA_CA<4>")
		)
		(pad "71" smd rect
			(at -2.050034 -3.824986 270)
			(size 0.519938 1.4986)
			(layers "F.Cu" "F.Mask" "F.Paste")
			(net "GND")
		)
		(pad "72" smd rect
			(at -2.050034 -2.975102 270)
			(size 0.519938 1.4986)
			(layers "F.Cu" "F.Mask" "F.Paste")
			(net "M_B_CPU0_SA_CA<6>")
		)
		(pad "73" smd rect
			(at -2.050034 -2.124964 270)
			(size 0.519938 1.4986)
			(layers "F.Cu" "F.Mask" "F.Paste")
			(net "GND")
		)
		(pad "74" smd rect
			(at -2.050034 -1.27508 270)
			(size 0.519938 1.4986)
			(layers "F.Cu" "F.Mask" "F.Paste")
			(net "M_B_CPU0_SA_PAR")
		)
		(pad "75" smd rect
			(at -2.050034 -0.424942 270)
			(size 0.519938 1.4986)
			(layers "F.Cu" "F.Mask" "F.Paste")
			(net "GND")
		)
		(pad "76" smd rect
			(at -2.050034 5.525008 270)
			(size 0.519938 1.4986)
			(layers "F.Cu" "F.Mask" "F.Paste")
			(net "M_B_CPU0_SB_CA<0>")
		)
		(pad "77" smd rect
			(at -2.050034 6.374892 270)
			(size 0.519938 1.4986)
			(layers "F.Cu" "F.Mask" "F.Paste")
			(net "GND")
		)
		(pad "78" smd rect
			(at -2.050034 7.22503 270)
			(size 0.519938 1.4986)
			(layers "F.Cu" "F.Mask" "F.Paste")
			(net "M_B_CPU0_SB_CA<2>")
		)
		(pad "79" smd rect
			(at -2.050034 8.074914 270)
			(size 0.519938 1.4986)
			(layers "F.Cu" "F.Mask" "F.Paste")
			(net "GND")
		)
		(pad "80" smd rect
			(at -2.050034 8.925052 270)
			(size 0.519938 1.4986)
			(layers "F.Cu" "F.Mask" "F.Paste")
			(net "M_B_CPU0_SB_CA<4>")
		)
		(pad "81" smd rect
			(at -2.050034 9.774936 270)
			(size 0.519938 1.4986)
			(layers "F.Cu" "F.Mask" "F.Paste")
			(net "GND")
		)
		(pad "82" smd rect
			(at -2.050034 10.625074 270)
			(size 0.519938 1.4986)
			(layers "F.Cu" "F.Mask" "F.Paste")
			(net "M_B_CPU0_SB_CA<6>")
		)
		(pad "83" smd rect
			(at -2.050034 11.474958 270)
			(size 0.519938 1.4986)
			(layers "F.Cu" "F.Mask" "F.Paste")
			(net "GND")
		)
		(pad "84" smd rect
			(at -2.050034 12.325096 270)
			(size 0.519938 1.4986)
			(layers "F.Cu" "F.Mask" "F.Paste")
			(net "M_B_CPU0_SB_CS_N<2>")
		)
		(pad "85" smd rect
			(at -2.050034 13.17498 270)
			(size 0.519938 1.4986)
			(layers "F.Cu" "F.Mask" "F.Paste")
			(net "GND")
		)
		(pad "86" smd rect
			(at -2.050034 14.025118 270)
			(size 0.519938 1.4986)
			(layers "F.Cu" "F.Mask" "F.Paste")
			(net "M_B_CPU0_SA_RSP<1>")
		)
		(pad "87" smd rect
			(at -2.050034 14.875002 270)
			(size 0.519938 1.4986)
			(layers "F.Cu" "F.Mask" "F.Paste")
			(net "M_B_CPU0_SB_RSP<1>")
		)
		(pad "88" smd rect
			(at -2.050034 15.724886 270)
			(size 0.519938 1.4986)
			(layers "F.Cu" "F.Mask" "F.Paste")
			(net "GND")
		)
		(pad "89" smd rect
			(at -2.050034 16.575024 270)
			(size 0.519938 1.4986)
			(layers "F.Cu" "F.Mask" "F.Paste")
			(net "M_B_CPU0_SB_CB<4>")
		)
		(pad "90" smd rect
			(at -2.050034 17.424908 270)
			(size 0.519938 1.4986)
			(layers "F.Cu" "F.Mask" "F.Paste")
			(net "GND")
		)
		(pad "91" smd rect
			(at -2.050034 18.275046 270)
			(size 0.519938 1.4986)
			(layers "F.Cu" "F.Mask" "F.Paste")
			(net "M_B_CPU0_SB_CB<5>")
		)
		(pad "92" smd rect
			(at -2.050034 19.12493 270)
			(size 0.519938 1.4986)
			(layers "F.Cu" "F.Mask" "F.Paste")
			(net "GND")
		)
		(pad "93" smd rect
			(at -2.050034 19.975068 270)
			(size 0.519938 1.4986)
			(layers "F.Cu" "F.Mask" "F.Paste")
			(net "M_B_CPU0_SB_DQS_DP<9>")
		)
		(pad "94" smd rect
			(at -2.050034 20.824952 270)
			(size 0.519938 1.4986)
			(layers "F.Cu" "F.Mask" "F.Paste")
			(net "M_B_CPU0_SB_DQS_DN<9>")
		)
		(pad "95" smd rect
			(at -2.050034 21.67509 270)
			(size 0.519938 1.4986)
			(layers "F.Cu" "F.Mask" "F.Paste")
			(net "GND")
		)
		(pad "96" smd rect
			(at -2.050034 22.524974 270)
			(size 0.519938 1.4986)
			(layers "F.Cu" "F.Mask" "F.Paste")
			(net "M_B_CPU0_SB_CB<0>")
		)
		(pad "97" smd rect
			(at -2.050034 23.375112 270)
			(size 0.519938 1.4986)
			(layers "F.Cu" "F.Mask" "F.Paste")
			(net "GND")
		)
		(pad "98" smd rect
			(at -2.050034 24.224996 270)
			(size 0.519938 1.4986)
			(layers "F.Cu" "F.Mask" "F.Paste")
			(net "M_B_CPU0_SB_CB<1>")
		)
		(pad "99" smd rect
			(at -2.050034 25.07488 270)
			(size 0.519938 1.4986)
			(layers "F.Cu" "F.Mask" "F.Paste")
			(net "GND")
		)
		(pad "100" smd rect
			(at -2.050034 25.925018 270)
			(size 0.519938 1.4986)
			(layers "F.Cu" "F.Mask" "F.Paste")
			(net "M_B_CPU0_SB_DQ<0>")
		)
		(pad "101" smd rect
			(at -2.050034 26.774902 270)
			(size 0.519938 1.4986)
			(layers "F.Cu" "F.Mask" "F.Paste")
			(net "GND")
		)
		(pad "102" smd rect
			(at -2.050034 27.62504 270)
			(size 0.519938 1.4986)
			(layers "F.Cu" "F.Mask" "F.Paste")
			(net "M_B_CPU0_SB_DQ<1>")
		)
		(pad "103" smd rect
			(at -2.050034 28.474924 270)
			(size 0.519938 1.4986)
			(layers "F.Cu" "F.Mask" "F.Paste")
			(net "GND")
		)
		(pad "104" smd rect
			(at -2.050034 29.325062 270)
			(size 0.519938 1.4986)
			(layers "F.Cu" "F.Mask" "F.Paste")
			(net "M_B_CPU0_SB_DQS_DP<0>")
		)
		(pad "105" smd rect
			(at -2.050034 30.174946 270)
			(size 0.519938 1.4986)
			(layers "F.Cu" "F.Mask" "F.Paste")
			(net "M_B_CPU0_SB_DQS_DN<0>")
		)
		(pad "106" smd rect
			(at -2.050034 31.025084 270)
			(size 0.519938 1.4986)
			(layers "F.Cu" "F.Mask" "F.Paste")
			(net "GND")
		)
		(pad "107" smd rect
			(at -2.050034 31.874968 270)
			(size 0.519938 1.4986)
			(layers "F.Cu" "F.Mask" "F.Paste")
			(net "M_B_CPU0_SB_DQ<4>")
		)
		(pad "108" smd rect
			(at -2.050034 32.725106 270)
			(size 0.519938 1.4986)
			(layers "F.Cu" "F.Mask" "F.Paste")
			(net "GND")
		)
		(pad "109" smd rect
			(at -2.050034 33.57499 270)
			(size 0.519938 1.4986)
			(layers "F.Cu" "F.Mask" "F.Paste")
			(net "M_B_CPU0_SB_DQ<5>")
		)
		(pad "110" smd rect
			(at -2.050034 34.425128 270)
			(size 0.519938 1.4986)
			(layers "F.Cu" "F.Mask" "F.Paste")
			(net "GND")
		)
		(pad "111" smd rect
			(at -2.050034 35.275012 270)
			(size 0.519938 1.4986)
			(layers "F.Cu" "F.Mask" "F.Paste")
			(net "M_B_CPU0_SB_DQ<8>")
		)
		(pad "112" smd rect
			(at -2.050034 36.124896 270)
			(size 0.519938 1.4986)
			(layers "F.Cu" "F.Mask" "F.Paste")
			(net "GND")
		)
	)
)
